# S9S_MB_2U (Grand Teton) — schematic netlist excerpt (pin names and nets, part order shuffled) for the footprints in the layout excerpt that follows; sources: Cadence DE-HDL packaged netlist, KiCad conversion of 03242023_DA0F0TMBIJ0_F0T_Motherboard_J_brd_V01_OCP.brd

PC1188_P0_4  Q_CAP  22UF 4V 20% X6S  pkg C0805  page 272 : A = PVCCFA_EHV_FIVRA_CPU0 ; B = GND
R1392  Q_RES  240 1% EMPTY  pkg 0402LF  page 120 : A = GND ; B = FM_S3M_CPU0_LVC1_GPIO_3
C464  Q_CAP  47UF 4V 20% X6S  pkg C0805  page 79 : A = PVCCFA_EHV_CPU1 ; B = GND

(kicad_pcb
	(version 20260206)
	(generator "pcbnew")
	(generator_version "10.0")
	(general
		(thickness 1.6)
		(legacy_teardrops no)
	)
	(paper "A4")
	(title_block
		(title "03242023_DA0F0TMBIJ0_F0T_Motherboard_J_brd_V01_OCP.brd")
		(comment 1 "Grand Teton / footprints 5954-5956 of 6105")
	)
	(layers
		(0 "F.Cu" signal "TOP")
		(4 "In1.Cu" signal "GND")
		(6 "In2.Cu" signal "IN1")
		(8 "In3.Cu" signal "GND1")
		(10 "In4.Cu" signal "IN2")
		(12 "In5.Cu" signal "GND2")
		(14 "In6.Cu" signal "IN3")
		(16 "In7.Cu" signal "GND3")
		(18 "In8.Cu" signal "VCC")
		(20 "In9.Cu" signal "VCC1")
		(22 "In10.Cu" signal "GND4")
		(24 "In11.Cu" signal "IN4")
		(26 "In12.Cu" signal "GND5")
		(28 "In13.Cu" signal "IN5")
		(30 "In14.Cu" signal "GND6")
		(32 "In15.Cu" signal "IN6")
		(34 "In16.Cu" signal "GND7")
		(2 "B.Cu" signal "BOTTOM")
		(9 "F.Adhes" user "F.Adhesive")
		(11 "B.Adhes" user "B.Adhesive")
		(13 "F.Paste" user "Package Geometry/Pastemask Top")
		(15 "B.Paste" user "Package Geometry/Pastemask Bottom")
		(5 "F.SilkS" user "Ref Des/Silkscreen Top")
		(7 "B.SilkS" user "Ref Des/Silkscreen Bottom")
		(1 "F.Mask" user "Board Geometry/Soldermask Top")
		(3 "B.Mask" user "Board Geometry/Soldermask Bottom")
		(17 "Dwgs.User" user "User.Drawings")
		(19 "Cmts.User" user "User.Comments")
		(21 "Eco1.User" user "User.Eco1")
		(23 "Eco2.User" user "User.Eco2")
		(25 "Edge.Cuts" user "Board Geometry/Outline")
		(27 "Margin" user)
		(31 "F.CrtYd" user "Package Geometry/Place Bound Top")
		(29 "B.CrtYd" user "Package Geometry/Place Bound Bottom")
		(35 "F.Fab" user "Ref Des/Assembly Top")
		(33 "B.Fab" user "Ref Des/Assembly Bottom")
	)
	(footprint ""
		(layer "B.Cu")
		(at 104.463088 -212.049868)
		(property "Reference" "C464"
			(at 0 0 0)
			(layer "B.SilkS")
			(hide yes)
			(effects
				(font
					(size 1.27 1.27)
				)
				(justify mirror)
			)
		)
		(property "Value" ""
			(at 0 0 0)
			(layer "B.Fab")
			(effects
				(font
					(size 1.27 1.27)
				)
				(justify mirror)
			)
		)
		(duplicate_pad_numbers_are_jumpers no)
		(fp_line
			(start -1.524 -0.762)
			(end -1.524 0.762)
			(stroke
				(width 0.1524)
				(type default)
			)
			(layer "B.SilkS")
		)
		(fp_line
			(start -1.524 0.762)
			(end 1.524 0.762)
			(stroke
				(width 0.1524)
				(type default)
			)
			(layer "B.SilkS")
		)
		(fp_line
			(start 1.524 -0.762)
			(end -1.524 -0.762)
			(stroke
				(width 0.1524)
				(type default)
			)
			(layer "B.SilkS")
		)
		(fp_line
			(start 1.524 0.762)
			(end 1.524 -0.762)
			(stroke
				(width 0.1524)
				(type default)
			)
			(layer "B.SilkS")
		)
		(fp_line
			(start -1.1049 -0.724916)
			(end 1.1049 -0.724916)
			(stroke
				(width 0.1)
				(type default)
			)
			(layer "B.Fab")
		)
		(fp_line
			(start -1.1049 0.724916)
			(end -1.1049 -0.724916)
			(stroke
				(width 0.1)
				(type default)
			)
			(layer "B.Fab")
		)
		(fp_line
			(start 1.1049 -0.724916)
			(end 1.1049 0.724916)
			(stroke
				(width 0.1)
				(type default)
			)
			(layer "B.Fab")
		)
		(fp_line
			(start 1.1049 0.724916)
			(end -1.1049 0.724916)
			(stroke
				(width 0.1)
				(type default)
			)
			(layer "B.Fab")
		)
		(pad "1" smd rect
			(at 0.889 0)
			(size 1.016 1.27)
			(layers "B.Cu" "B.Mask" "B.Paste")
			(net "PVCCFA_EHV_CPU1")
		)
		(pad "2" smd rect
			(at -0.889 0)
			(size 1.016 1.27)
			(layers "B.Cu" "B.Mask" "B.Paste")
			(net "GND")
		)
	)
	(footprint ""
		(layer "B.Cu")
		(at 280.110184 -193.669666 -90)
		(property "Reference" "R1392"
			(at 0 0 90)
			(layer "B.SilkS")
			(hide yes)
			(effects
				(font
					(size 1.27 1.27)
				)
				(justify mirror)
			)
		)
		(property "Value" ""
			(at 0 0 90)
			(layer "B.Fab")
			(effects
				(font
					(size 1.27 1.27)
				)
				(justify mirror)
			)
		)
		(duplicate_pad_numbers_are_jumpers no)
		(fp_line
			(start -0.7874 0.4064)
			(end 0.7874 0.4064)
			(stroke
				(width 0.1524)
				(type default)
			)
			(layer "B.SilkS")
		)
		(fp_line
			(start 0.7874 0.4064)
			(end 0.7874 -0.4064)
			(stroke
				(width 0.1524)
				(type default)
			)
			(layer "B.SilkS")
		)
		(fp_line
			(start -0.7874 -0.4064)
			(end -0.7874 0.4064)
			(stroke
				(width 0.1524)
				(type default)
			)
			(layer "B.SilkS")
		)
		(fp_line
			(start 0.7874 -0.4064)
			(end -0.7874 -0.4064)
			(stroke
				(width 0.1524)
				(type default)
			)
			(layer "B.SilkS")
		)
		(fp_line
			(start -0.67945 0.3048)
			(end -0.120396 0.3048)
			(stroke
				(width 0.1)
				(type default)
			)
			(layer "B.Fab")
		)
		(fp_line
			(start -0.120396 0.3048)
			(end -0.120396 0.2794)
			(stroke
				(width 0.1)
				(type default)
			)
			(layer "B.Fab")
		)
		(fp_line
			(start 0.12065 0.3048)
			(end 0.67945 0.3048)
			(stroke
				(width 0.1)
				(type default)
			)
			(layer "B.Fab")
		)
		(fp_line
			(start 0.67945 0.3048)
			(end 0.67945 -0.305054)
			(stroke
				(width 0.1)
				(type default)
			)
			(layer "B.Fab")
		)
		(fp_line
			(start -0.120396 0.2794)
			(end 0.12065 0.2794)
			(stroke
				(width 0.1)
				(type default)
			)
			(layer "B.Fab")
		)
		(fp_line
			(start 0.12065 0.2794)
			(end 0.12065 0.3048)
			(stroke
				(width 0.1)
				(type default)
			)
			(layer "B.Fab")
		)
		(fp_line
			(start -0.12065 -0.2794)
			(end -0.12065 -0.3048)
			(stroke
				(width 0.1)
				(type default)
			)
			(layer "B.Fab")
		)
		(fp_line
			(start 0.12065 -0.2794)
			(end -0.12065 -0.2794)
			(stroke
				(width 0.1)
				(type default)
			)
			(layer "B.Fab")
		)
		(fp_line
			(start -0.67945 -0.3048)
			(end -0.67945 0.3048)
			(stroke
				(width 0.1)
				(type default)
			)
			(layer "B.Fab")
		)
		(fp_line
			(start -0.12065 -0.3048)
			(end -0.67945 -0.3048)
			(stroke
				(width 0.1)
				(type default)
			)
			(layer "B.Fab")
		)
		(fp_line
			(start 0.12065 -0.305054)
			(end 0.12065 -0.2794)
			(stroke
				(width 0.1)
				(type default)
			)
			(layer "B.Fab")
		)
		(fp_line
			(start 0.67945 -0.305054)
			(end 0.12065 -0.305054)
			(stroke
				(width 0.1)
				(type default)
			)
			(layer "B.Fab")
		)
		(pad "1" smd circle
			(at 0.40005 0 90)
			(size 0 0)
			(layers "B.Cu" "B.Mask" "B.Paste")
			(net "GND")
		)
		(pad "2" smd circle
			(at -0.40005 0 90)
			(size 0 0)
			(layers "B.Cu" "B.Mask" "B.Paste")
			(net "FM_S3M_CPU0_LVC1_GPIO_3")
		)
	)
	(footprint ""
		(layer "B.Cu")
		(at 285.23692 -354.163376 -90)
		(property "Reference" "PC1188_P0_4"
			(at 0 0 90)
			(layer "B.SilkS")
			(hide yes)
			(effects
				(font
					(size 1.27 1.27)
				)
				(justify mirror)
			)
		)
		(property "Value" ""
			(at 0 0 90)
			(layer "B.Fab")
			(effects
				(font
					(size 1.27 1.27)
				)
				(justify mirror)
			)
		)
		(duplicate_pad_numbers_are_jumpers no)
		(fp_line
			(start -1.524 0.762)
			(end 1.524 0.762)
			(stroke
				(width 0.1524)
				(type default)
			)
			(layer "B.SilkS")
		)
		(fp_line
			(start 1.524 0.762)
			(end 1.524 -0.762)
			(stroke
				(width 0.1524)
				(type default)
			)
			(layer "B.SilkS")
		)
		(fp_line
			(start -1.524 -0.762)
			(end -1.524 0.762)
			(stroke
				(width 0.1524)
				(type default)
			)
			(layer "B.SilkS")
		)
		(fp_line
			(start 1.524 -0.762)
			(end -1.524 -0.762)
			(stroke
				(width 0.1524)
				(type default)
			)
			(layer "B.SilkS")
		)
		(fp_line
			(start -1.1049 0.724916)
			(end -1.1049 -0.724916)
			(stroke
				(width 0.1)
				(type default)
			)
			(layer "B.Fab")
		)
		(fp_line
			(start 1.1049 0.724916)
			(end -1.1049 0.724916)
			(stroke
				(width 0.1)
				(type default)
			)
			(layer "B.Fab")
		)
		(fp_line
			(start -1.1049 -0.724916)
			(end 1.1049 -0.724916)
			(stroke
				(width 0.1)
				(type default)
			)
			(layer "B.Fab")
		)
		(fp_line
			(start 1.1049 -0.724916)
			(end 1.1049 0.724916)
			(stroke
				(width 0.1)
				(type default)
			)
			(layer "B.Fab")
		)
		(pad "1" smd rect
			(at 0.889 0 270)
			(size 1.016 1.27)
			(layers "B.Cu" "B.Mask" "B.Paste")
			(net "PVCCFA_EHV_FIVRA_CPU0")
		)
		(pad "2" smd rect
			(at -0.889 0 270)
			(size 1.016 1.27)
			(layers "B.Cu" "B.Mask" "B.Paste")
			(net "GND")
		)
	)
)
